(kicad_pcb
	(version 20260206)
	(generator "pcbnew")
	(generator_version "10.0")
	(general
		(thickness 1.6)
		(legacy_teardrops no)
	)
	(paper "A4")
	(title_block
		(title "netronome-mezz — pcbd0082-001_rev01_jul9_a.brd")
		(comment 1 "Open CloudServer (Microsoft) / footprints 314-321 of 714")
	)
	(layers
		(0 "F.Cu" signal "TOP")
		(4 "In1.Cu" signal "02_GND")
		(6 "In2.Cu" signal "03_SIG")
		(8 "In3.Cu" signal "04_SIG")
		(10 "In4.Cu" signal "05_GND")
		(12 "In5.Cu" signal "06_PWR1")
		(14 "In6.Cu" signal "07_SIG")
		(16 "In7.Cu" signal "08_SIG")
		(18 "In8.Cu" signal "09_GND")
		(2 "B.Cu" signal "BOTTOM")
		(9 "F.Adhes" user "F.Adhesive")
		(11 "B.Adhes" user "B.Adhesive")
		(13 "F.Paste" user "Package Geometry/Pastemask Top")
		(15 "B.Paste" user "Package Geometry/Pastemask Bottom")
		(5 "F.SilkS" user "Ref Des/Silkscreen Top")
		(7 "B.SilkS" user "Ref Des/Silkscreen Bottom")
		(1 "F.Mask" user "Board Geometry/Soldermask Top")
		(3 "B.Mask" user "Board Geometry/Soldermask Bottom")
		(17 "Dwgs.User" user "User.Drawings")
		(19 "Cmts.User" user "User.Comments")
		(21 "Eco1.User" user "User.Eco1")
		(23 "Eco2.User" user "User.Eco2")
		(25 "Edge.Cuts" user "Board Geometry/Outline")
		(27 "Margin" user)
		(31 "F.CrtYd" user "Package Geometry/Place Bound Top")
		(29 "B.CrtYd" user "Package Geometry/Place Bound Bottom")
		(35 "F.Fab" user "Ref Des/Assembly Top")
		(33 "B.Fab" user "Ref Des/Assembly Bottom")
		(45 "User.4" user "COMPVAL_TYPE_BOTTOM")
	)
	(footprint ""
		(layer "B.Cu")
		(at 45.237019 29.541978)
		(property "Reference" "C167"
			(at -1.575689 -0.077978 270)
			(unlocked yes)
			(layer "B.SilkS")
			(effects
				(font
					(size 0.7874 0.5842)
					(thickness 0.127)
				)
				(justify mirror)
			)
		)
		(property "Value" ""
			(at 0 0 0)
			(layer "B.Fab")
			(effects
				(font
					(size 1.27 1.27)
				)
				(justify mirror)
			)
		)
		(duplicate_pad_numbers_are_jumpers no)
		(fp_circle
			(center 0 0)
			(end 0.104648 0)
			(stroke
				(width 0.1016)
				(type default)
			)
			(fill no)
			(layer "B.SilkS")
		)
		(fp_poly
			(pts
				(xy 0.381 -0.889) (xy 0.381 0.889) (xy -0.381 0.889) (xy -0.381 -0.889)
			)
			(stroke
				(width 0)
				(type default)
			)
			(fill no)
			(layer "B.CrtYd")
		)
		(fp_line
			(start -0.508 -1.016)
			(end -0.508 1.016)
			(stroke
				(width 0.0254)
				(type default)
			)
			(layer "B.Fab")
		)
		(fp_line
			(start -0.508 1.016)
			(end 0.508 1.016)
			(stroke
				(width 0.0254)
				(type default)
			)
			(layer "B.Fab")
		)
		(fp_line
			(start 0.254 -1.016)
			(end -0.508 -1.016)
			(stroke
				(width 0.0254)
				(type default)
			)
			(layer "B.Fab")
		)
		(fp_line
			(start 0.508 -1.016)
			(end 0.254 -1.016)
			(stroke
				(width 0.0254)
				(type default)
			)
			(layer "B.Fab")
		)
		(fp_line
			(start 0.508 1.016)
			(end 0.508 -1.016)
			(stroke
				(width 0.0254)
				(type default)
			)
			(layer "B.Fab")
		)
		(pad "1" smd custom
			(at 0 -0.500126 180)
			(size 0.127 0.127)
			(layers "B.Cu" "B.Mask" "B.Paste")
			(net "VDD_CORE")
			(options
				(clearance outline)
				(anchor circle)
			)
			(primitives
				(gr_poly
					(pts
						(xy -0.1778 0.254) (xy 0.1778 0.254) (xy 0.254 0.1778) (xy 0.254 -0.1778) (xy 0.1778 -0.254) (xy -0.1778 -0.254)
						(xy -0.254 -0.1778) (xy -0.254 0.1778)
					)
					(width 0)
					(fill yes)
				)
			)
		)
		(pad "2" smd custom
			(at 0 0.500126 180)
			(size 0.127 0.127)
			(layers "B.Cu" "B.Mask" "B.Paste")
			(net "GND")
			(options
				(clearance outline)
				(anchor circle)
			)
			(primitives
				(gr_poly
					(pts
						(xy -0.1778 0.254) (xy 0.1778 0.254) (xy 0.254 0.1778) (xy 0.254 -0.1778) (xy 0.1778 -0.254) (xy -0.1778 -0.254)
						(xy -0.254 -0.1778) (xy -0.254 0.1778)
					)
					(width 0)
					(fill yes)
				)
			)
		)
	)
	(footprint ""
		(layer "B.Cu")
		(at 26.924 20.5232 180)
		(property "Reference" "R56"
			(at 0 0 0)
			(layer "B.SilkS")
			(hide yes)
			(effects
				(font
					(size 1.27 1.27)
				)
				(justify mirror)
			)
		)
		(property "Value" "4.75K"
			(at 0.148158 1.3462 90)
			(unlocked yes)
			(layer "B.Fab")
			(hide yes)
			(effects
				(font
					(size 1.27 0.9652)
					(thickness 0.000001)
				)
				(justify left mirror)
			)
		)
		(property "Device Type" "REST4024"
			(at 0.148158 1.3462 90)
			(unlocked yes)
			(layer "B.Fab")
			(hide yes)
			(effects
				(font
					(size 1.27 0.9652)
					(thickness 0.000001)
				)
				(justify left mirror)
			)
		)
		(duplicate_pad_numbers_are_jumpers no)
		(fp_poly
			(pts
				(xy -0.635 1.0668) (xy -0.635 -1.0668) (xy 0.635 -1.0668) (xy 0.635 1.0668)
			)
			(stroke
				(width 0)
				(type default)
			)
			(fill no)
			(layer "B.CrtYd")
		)
		(fp_line
			(start 0.254 0.508)
			(end 0.254 -0.508)
			(stroke
				(width 0.0254)
				(type default)
			)
			(layer "B.Fab")
		)
		(fp_line
			(start 0.254 -0.508)
			(end -0.254 -0.508)
			(stroke
				(width 0.0254)
				(type default)
			)
			(layer "B.Fab")
		)
		(fp_line
			(start -0.254 0.508)
			(end 0.254 0.508)
			(stroke
				(width 0.0254)
				(type default)
			)
			(layer "B.Fab")
		)
		(fp_line
			(start -0.254 -0.508)
			(end -0.254 0.508)
			(stroke
				(width 0.0254)
				(type default)
			)
			(layer "B.Fab")
		)
		(pad "1" smd rect
			(at 0 -0.4191)
			(size 0.508 0.5334)
			(layers "B.Cu" "B.Mask" "B.Paste")
			(net "NFP_PGOOD4")
		)
		(pad "2" smd rect
			(at 0 0.4191)
			(size 0.508 0.5334)
			(layers "B.Cu" "B.Mask" "B.Paste")
			(net "GND")
		)
		(zone
			(layer "B.Cu")
			(hatch none 0.5)
			(connect_pads
				(clearance 0)
			)
			(min_thickness 0.25)
			(keepout
				(tracks not_allowed)
				(vias allowed)
				(pads allowed)
				(copperpour not_allowed)
				(footprints allowed)
			)
			(placement
				(enabled no)
				(sheetname "")
			)
			(fill
				(thermal_gap 0.5)
				(thermal_bridge_width 0.5)
				(island_removal_mode 0)
			)
			(polygon
				(pts
					(xy 26.9494 20.5486) (xy 26.9494 20.4978) (xy 26.8986 20.4978) (xy 26.8986 20.5486)
				)
			)
		)
	)
	(footprint ""
		(layer "B.Cu")
		(at 47.1551 18.542 90)
		(property "Reference" "C4"
			(at 1.37033 1.397 0)
			(unlocked yes)
			(layer "B.SilkS")
			(effects
				(font
					(size 0.7874 0.5842)
					(thickness 0.127)
				)
				(justify left mirror)
			)
		)
		(property "Value" "22UF"
			(at 0.148158 1.7526 0)
			(unlocked yes)
			(layer "B.Fab")
			(hide yes)
			(effects
				(font
					(size 1.27 0.9652)
					(thickness 0.000001)
				)
				(justify left mirror)
			)
		)
		(property "Device Type" "CAPC0063"
			(at 0.148158 1.7526 0)
			(unlocked yes)
			(layer "B.Fab")
			(hide yes)
			(effects
				(font
					(size 1.27 0.9652)
					(thickness 0.000001)
				)
				(justify left mirror)
			)
		)
		(duplicate_pad_numbers_are_jumpers no)
		(fp_circle
			(center 0 0)
			(end 0 0.127)
			(stroke
				(width 0.2032)
				(type default)
			)
			(fill no)
			(layer "B.SilkS")
		)
		(fp_poly
			(pts
				(xy -0.7874 -1.6637) (xy 0.7874 -1.6637) (xy 0.7874 1.6637) (xy -0.7874 1.6637)
			)
			(stroke
				(width 0)
				(type default)
			)
			(fill no)
			(layer "B.CrtYd")
		)
		(fp_line
			(start 0.4064 -0.7874)
			(end -0.4064 -0.7874)
			(stroke
				(width 0.0254)
				(type default)
			)
			(layer "B.Fab")
		)
		(fp_line
			(start -0.4064 -0.7874)
			(end -0.4064 0.8128)
			(stroke
				(width 0.0254)
				(type default)
			)
			(layer "B.Fab")
		)
		(fp_line
			(start 0.4064 0.8128)
			(end 0.4064 -0.7874)
			(stroke
				(width 0.0254)
				(type default)
			)
			(layer "B.Fab")
		)
		(fp_line
			(start -0.4064 0.8128)
			(end 0.4064 0.8128)
			(stroke
				(width 0.0254)
				(type default)
			)
			(layer "B.Fab")
		)
		(pad "1" smd rect
			(at 0 -0.8001 270)
			(size 0.8636 0.9652)
			(layers "B.Cu" "B.Mask" "B.Paste")
			(net "VDD_CORE")
		)
		(pad "2" smd rect
			(at 0 0.8001 270)
			(size 0.8636 0.9652)
			(layers "B.Cu" "B.Mask" "B.Paste")
			(net "GND")
		)
		(zone
			(layer "B.Cu")
			(hatch none 0.5)
			(connect_pads
				(clearance 0)
			)
			(min_thickness 0.25)
			(keepout
				(tracks not_allowed)
				(vias allowed)
				(pads allowed)
				(copperpour not_allowed)
				(footprints allowed)
			)
			(placement
				(enabled no)
				(sheetname "")
			)
			(fill
				(thermal_gap 0.5)
				(thermal_bridge_width 0.5)
				(island_removal_mode 0)
			)
			(polygon
				(pts
					(xy 46.9011 18.4785) (xy 46.9011 18.6055) (xy 47.4091 18.6055) (xy 47.4091 18.4785)
				)
			)
		)
	)
	(footprint ""
		(layer "B.Cu")
		(at 45.085 46.101)
		(property "Reference" "TP25"
			(at 4.191 0.28067 0)
			(unlocked yes)
			(layer "B.SilkS")
			(effects
				(font
					(size 0.7874 0.5842)
					(thickness 0.127)
				)
				(justify left mirror)
			)
		)
		(property "Value" "*"
			(at 0.4826 -0.14732 0)
			(unlocked yes)
			(layer "B.Fab")
			(hide yes)
			(effects
				(font
					(size 1.27 0.9652)
					(thickness 0.000001)
				)
				(justify left mirror)
			)
		)
		(property "Device Type" "TP_SMALL"
			(at 0.4826 -0.14732 0)
			(unlocked yes)
			(layer "B.Fab")
			(hide yes)
			(effects
				(font
					(size 1.27 0.9652)
					(thickness 0.000001)
				)
				(justify left mirror)
			)
		)
		(duplicate_pad_numbers_are_jumpers no)
		(fp_line
			(start -0.8636 -0.8636)
			(end 0.8636 -0.8636)
			(stroke
				(width 0.1524)
				(type default)
			)
			(layer "B.SilkS")
		)
		(fp_line
			(start -0.8636 0.8636)
			(end -0.8636 -0.8636)
			(stroke
				(width 0.1524)
				(type default)
			)
			(layer "B.SilkS")
		)
		(fp_line
			(start 0.8636 -0.8636)
			(end 0.8636 0.8636)
			(stroke
				(width 0.1524)
				(type default)
			)
			(layer "B.SilkS")
		)
		(fp_line
			(start 0.8636 0.8636)
			(end -0.8636 0.8636)
			(stroke
				(width 0.1524)
				(type default)
			)
			(layer "B.SilkS")
		)
		(fp_poly
			(pts
				(xy 0.635 -0.635) (xy 0.635 0.635) (xy -0.635 0.635) (xy -0.635 -0.635)
			)
			(stroke
				(width 0)
				(type default)
			)
			(fill no)
			(layer "B.CrtYd")
		)
		(pad "1" smd rect
			(at 0 0 180)
			(size 1.27 1.27)
			(layers "B.Cu" "B.Mask" "B.Paste")
			(net "NFP_UART_SR_RX")
		)
	)
	(footprint ""
		(layer "B.Cu")
		(at 32.512 28.321 180)
		(property "Reference" "R264"
			(at 0.381 -0.66167 0)
			(unlocked yes)
			(layer "B.SilkS")
			(effects
				(font
					(size 0.7874 0.5842)
					(thickness 0.127)
				)
				(justify left mirror)
			)
		)
		(property "Value" "39.0"
			(at 0.148158 1.3462 90)
			(unlocked yes)
			(layer "B.Fab")
			(hide yes)
			(effects
				(font
					(size 1.27 0.9652)
					(thickness 0.000001)
				)
				(justify left mirror)
			)
		)
		(property "Device Type" "REST0108"
			(at 0.148158 1.3462 90)
			(unlocked yes)
			(layer "B.Fab")
			(hide yes)
			(effects
				(font
					(size 1.27 0.9652)
					(thickness 0.000001)
				)
				(justify left mirror)
			)
		)
		(duplicate_pad_numbers_are_jumpers no)
		(fp_poly
			(pts
				(xy -0.635 1.0668) (xy -0.635 -1.0668) (xy 0.635 -1.0668) (xy 0.635 1.0668)
			)
			(stroke
				(width 0)
				(type default)
			)
			(fill no)
			(layer "B.CrtYd")
		)
		(fp_line
			(start 0.254 0.508)
			(end 0.254 -0.508)
			(stroke
				(width 0.0254)
				(type default)
			)
			(layer "B.Fab")
		)
		(fp_line
			(start 0.254 -0.508)
			(end -0.254 -0.508)
			(stroke
				(width 0.0254)
				(type default)
			)
			(layer "B.Fab")
		)
		(fp_line
			(start -0.254 0.508)
			(end 0.254 0.508)
			(stroke
				(width 0.0254)
				(type default)
			)
			(layer "B.Fab")
		)
		(fp_line
			(start -0.254 -0.508)
			(end -0.254 0.508)
			(stroke
				(width 0.0254)
				(type default)
			)
			(layer "B.Fab")
		)
		(pad "1" smd rect
			(at 0 -0.4191)
			(size 0.508 0.5334)
			(layers "B.Cu" "B.Mask" "B.Paste")
			(net "9N1879")
		)
		(pad "2" smd rect
			(at 0 0.4191)
			(size 0.508 0.5334)
			(layers "B.Cu" "B.Mask" "B.Paste")
			(net "CPLD_PGRM_JTAG_TDO")
		)
		(zone
			(layer "B.Cu")
			(hatch none 0.5)
			(connect_pads
				(clearance 0)
			)
			(min_thickness 0.25)
			(keepout
				(tracks not_allowed)
				(vias allowed)
				(pads allowed)
				(copperpour not_allowed)
				(footprints allowed)
			)
			(placement
				(enabled no)
				(sheetname "")
			)
			(fill
				(thermal_gap 0.5)
				(thermal_bridge_width 0.5)
				(island_removal_mode 0)
			)
			(polygon
				(pts
					(xy 32.5374 28.3464) (xy 32.5374 28.2956) (xy 32.4866 28.2956) (xy 32.4866 28.3464)
				)
			)
		)
	)
	(footprint ""
		(layer "B.Cu")
		(at 49.73701 11.042015 90)
		(property "Reference" "C94"
			(at 0 0 90)
			(layer "B.SilkS")
			(hide yes)
			(effects
				(font
					(size 1.27 1.27)
				)
				(justify mirror)
			)
		)
		(property "Value" ""
			(at 0 0 90)
			(layer "B.Fab")
			(effects
				(font
					(size 1.27 1.27)
				)
				(justify mirror)
			)
		)
		(duplicate_pad_numbers_are_jumpers no)
		(fp_circle
			(center 0 0)
			(end 0 0.104648)
			(stroke
				(width 0.1016)
				(type default)
			)
			(fill no)
			(layer "B.SilkS")
		)
		(fp_poly
			(pts
				(xy 0.381 -0.889) (xy 0.381 0.889) (xy -0.381 0.889) (xy -0.381 -0.889)
			)
			(stroke
				(width 0)
				(type default)
			)
			(fill no)
			(layer "B.CrtYd")
		)
		(fp_line
			(start 0.508 -1.016)
			(end 0.254 -1.016)
			(stroke
				(width 0.0254)
				(type default)
			)
			(layer "B.Fab")
		)
		(fp_line
			(start 0.254 -1.016)
			(end -0.508 -1.016)
			(stroke
				(width 0.0254)
				(type default)
			)
			(layer "B.Fab")
		)
		(fp_line
			(start -0.508 -1.016)
			(end -0.508 1.016)
			(stroke
				(width 0.0254)
				(type default)
			)
			(layer "B.Fab")
		)
		(fp_line
			(start 0.508 1.016)
			(end 0.508 -1.016)
			(stroke
				(width 0.0254)
				(type default)
			)
			(layer "B.Fab")
		)
		(fp_line
			(start -0.508 1.016)
			(end 0.508 1.016)
			(stroke
				(width 0.0254)
				(type default)
			)
			(layer "B.Fab")
		)
		(pad "1" smd custom
			(at 0 -0.500126 270)
			(size 0.127 0.127)
			(layers "B.Cu" "B.Mask" "B.Paste")
			(net "VDDA_SERDES")
			(options
				(clearance outline)
				(anchor circle)
			)
			(primitives
				(gr_poly
					(pts
						(xy -0.1778 0.254) (xy 0.1778 0.254) (xy 0.254 0.1778) (xy 0.254 -0.1778) (xy 0.1778 -0.254) (xy -0.1778 -0.254)
						(xy -0.254 -0.1778) (xy -0.254 0.1778)
					)
					(width 0)
					(fill yes)
				)
			)
		)
		(pad "2" smd custom
			(at 0 0.500126 270)
			(size 0.127 0.127)
			(layers "B.Cu" "B.Mask" "B.Paste")
			(net "GND")
			(options
				(clearance outline)
				(anchor circle)
			)
			(primitives
				(gr_poly
					(pts
						(xy -0.1778 0.254) (xy 0.1778 0.254) (xy 0.254 0.1778) (xy 0.254 -0.1778) (xy 0.1778 -0.254) (xy -0.1778 -0.254)
						(xy -0.254 -0.1778) (xy -0.254 0.1778)
					)
					(width 0)
					(fill yes)
				)
			)
		)
	)
	(footprint ""
		(layer "B.Cu")
		(at 37.6428 20.193 -90)
		(property "Reference" "R281"
			(at 0 0 90)
			(layer "B.SilkS")
			(hide yes)
			(effects
				(font
					(size 1.27 1.27)
				)
				(justify mirror)
			)
		)
		(property "Value" "100"
			(at 0.148158 1.3462 180)
			(unlocked yes)
			(layer "B.Fab")
			(hide yes)
			(effects
				(font
					(size 1.27 0.9652)
					(thickness 0.000001)
				)
				(justify left mirror)
			)
		)
		(property "Device Type" "REST4030"
			(at 0.148158 1.3462 180)
			(unlocked yes)
			(layer "B.Fab")
			(hide yes)
			(effects
				(font
					(size 1.27 0.9652)
					(thickness 0.000001)
				)
				(justify left mirror)
			)
		)
		(duplicate_pad_numbers_are_jumpers no)
		(fp_poly
			(pts
				(xy -0.635 1.0668) (xy -0.635 -1.0668) (xy 0.635 -1.0668) (xy 0.635 1.0668)
			)
			(stroke
				(width 0)
				(type default)
			)
			(fill no)
			(layer "B.CrtYd")
		)
		(fp_line
			(start -0.254 0.508)
			(end 0.254 0.508)
			(stroke
				(width 0.0254)
				(type default)
			)
			(layer "B.Fab")
		)
		(fp_line
			(start 0.254 0.508)
			(end 0.254 -0.508)
			(stroke
				(width 0.0254)
				(type default)
			)
			(layer "B.Fab")
		)
		(fp_line
			(start -0.254 -0.508)
			(end -0.254 0.508)
			(stroke
				(width 0.0254)
				(type default)
			)
			(layer "B.Fab")
		)
		(fp_line
			(start 0.254 -0.508)
			(end -0.254 -0.508)
			(stroke
				(width 0.0254)
				(type default)
			)
			(layer "B.Fab")
		)
		(pad "1" smd rect
			(at 0 -0.4191 90)
			(size 0.508 0.5334)
			(layers "B.Cu" "B.Mask" "B.Paste")
			(net "_NFP_CFG_SPI_FLASH_SEL")
		)
		(pad "2" smd rect
			(at 0 0.4191 90)
			(size 0.508 0.5334)
			(layers "B.Cu" "B.Mask" "B.Paste")
			(net "NFP_CFG_SPI_FLASH_SEL")
		)
		(zone
			(layer "B.Cu")
			(hatch none 0.5)
			(connect_pads
				(clearance 0)
			)
			(min_thickness 0.25)
			(keepout
				(tracks not_allowed)
				(vias allowed)
				(pads allowed)
				(copperpour not_allowed)
				(footprints allowed)
			)
			(placement
				(enabled no)
				(sheetname "")
			)
			(fill
				(thermal_gap 0.5)
				(thermal_bridge_width 0.5)
				(island_removal_mode 0)
			)
			(polygon
				(pts
					(xy 37.6682 20.1676) (xy 37.6174 20.1676) (xy 37.6174 20.2184) (xy 37.6682 20.2184)
				)
			)
		)
	)
	(footprint ""
		(layer "B.Cu")
		(at 27.686 16.764 180)
		(property "Reference" "R149"
			(at 0.91567 -0.508 270)
			(unlocked yes)
			(layer "B.SilkS")
			(effects
				(font
					(size 0.7874 0.5842)
					(thickness 0.127)
				)
				(justify left mirror)
			)
		)
		(property "Value" "0"
			(at 0.148158 1.3462 90)
			(unlocked yes)
			(layer "B.Fab")
			(hide yes)
			(effects
				(font
					(size 1.27 0.9652)
					(thickness 0.000001)
				)
				(justify left mirror)
			)
		)
		(property "Device Type" "REST1111"
			(at 0.148158 1.3462 90)
			(unlocked yes)
			(layer "B.Fab")
			(hide yes)
			(effects
				(font
					(size 1.27 0.9652)
					(thickness 0.000001)
				)
				(justify left mirror)
			)
		)
		(duplicate_pad_numbers_are_jumpers no)
		(fp_poly
			(pts
				(xy -0.635 1.0668) (xy -0.635 -1.0668) (xy 0.635 -1.0668) (xy 0.635 1.0668)
			)
			(stroke
				(width 0)
				(type default)
			)
			(fill no)
			(layer "B.CrtYd")
		)
		(fp_line
			(start 0.254 0.508)
			(end 0.254 -0.508)
			(stroke
				(width 0.0254)
				(type default)
			)
			(layer "B.Fab")
		)
		(fp_line
			(start 0.254 -0.508)
			(end -0.254 -0.508)
			(stroke
				(width 0.0254)
				(type default)
			)
			(layer "B.Fab")
		)
		(fp_line
			(start -0.254 0.508)
			(end 0.254 0.508)
			(stroke
				(width 0.0254)
				(type default)
			)
			(layer "B.Fab")
		)
		(fp_line
			(start -0.254 -0.508)
			(end -0.254 0.508)
			(stroke
				(width 0.0254)
				(type default)
			)
			(layer "B.Fab")
		)
		(pad "1" smd rect
			(at 0 -0.4191)
			(size 0.508 0.5334)
			(layers "B.Cu" "B.Mask" "B.Paste")
			(net "GND")
		)
		(pad "2" smd rect
			(at 0 0.4191)
			(size 0.508 0.5334)
			(layers "B.Cu" "B.Mask" "B.Paste")
			(net "MH_2")
		)
		(zone
			(layer "B.Cu")
			(hatch none 0.5)
			(connect_pads
				(clearance 0)
			)
			(min_thickness 0.25)
			(keepout
				(tracks not_allowed)
				(vias allowed)
				(pads allowed)
				(copperpour not_allowed)
				(footprints allowed)
			)
			(placement
				(enabled no)
				(sheetname "")
			)
			(fill
				(thermal_gap 0.5)
				(thermal_bridge_width 0.5)
				(island_removal_mode 0)
			)
			(polygon
				(pts
					(xy 27.7114 16.7894) (xy 27.7114 16.7386) (xy 27.6606 16.7386) (xy 27.6606 16.7894)
				)
			)
		)
	)
)
